(kicad_pcb
	(version 20260206)
	(generator "pcbnew")
	(generator_version "10.0")
	(general
		(thickness 1.6)
		(legacy_teardrops no)
	)
	(paper "A4")
	(title_block
		(title "Wiwynn_Tioga_Pass_MB.brd")
		(comment 1 "Tioga Pass / footprints 760-767 of 4770")
	)
	(layers
		(0 "F.Cu" signal "TOP")
		(4 "In1.Cu" signal "L2GND")
		(6 "In2.Cu" signal "L3")
		(8 "In3.Cu" signal "L4GND")
		(10 "In4.Cu" signal "L5")
		(12 "In5.Cu" signal "L6GND")
		(14 "In6.Cu" signal "L7VCC")
		(16 "In7.Cu" signal "L8VCC")
		(18 "In8.Cu" signal "L9GND")
		(20 "In9.Cu" signal "L10")
		(22 "In10.Cu" signal "L11GND")
		(24 "In11.Cu" signal "L12")
		(26 "In12.Cu" signal "L13GND")
		(2 "B.Cu" signal "BOTTOM")
		(9 "F.Adhes" user "F.Adhesive")
		(11 "B.Adhes" user "B.Adhesive")
		(13 "F.Paste" user "Package Geometry/Pastemask Top")
		(15 "B.Paste" user "Package Geometry/Pastemask Bottom")
		(5 "F.SilkS" user "Ref Des/Silkscreen Top")
		(7 "B.SilkS" user "Ref Des/Silkscreen Bottom")
		(1 "F.Mask" user "Board Geometry/Soldermask Top")
		(3 "B.Mask" user "Board Geometry/Soldermask Bottom")
		(17 "Dwgs.User" user "User.Drawings")
		(19 "Cmts.User" user "User.Comments")
		(21 "Eco1.User" user "User.Eco1")
		(23 "Eco2.User" user "User.Eco2")
		(25 "Edge.Cuts" user "Board Geometry/Outline")
		(27 "Margin" user)
		(31 "F.CrtYd" user "Package Geometry/Place Bound Top")
		(29 "B.CrtYd" user "Package Geometry/Place Bound Bottom")
		(35 "F.Fab" user "Ref Des/Assembly Top")
		(33 "B.Fab" user "Ref Des/Assembly Bottom")
	)
	(footprint ""
		(layer "F.Cu")
		(at 425.919646 -48.968152)
		(property "Reference" "R25W100"
			(at -0.8382 -0.67818 0)
			(unlocked yes)
			(layer "F.SilkS")
			(effects
				(font
					(size 0.4064 0.254)
					(thickness 0.1524)
				)
				(justify left)
			)
		)
		(property "Value" ""
			(at 0 0 0)
			(layer "F.Fab")
			(effects
				(font
					(size 1.27 1.27)
				)
			)
		)
		(duplicate_pad_numbers_are_jumpers no)
		(fp_poly
			(pts
				(xy -0.2794 -0.1016) (xy 0.2794 -0.1016) (xy 0.2794 0.9906) (xy -0.2794 0.9906)
			)
			(stroke
				(width 0)
				(type default)
			)
			(fill no)
			(layer "F.CrtYd")
		)
		(fp_line
			(start -0.2794 -0.1016)
			(end -0.2794 0.9906)
			(stroke
				(width 0.1)
				(type default)
			)
			(layer "F.Fab")
		)
		(fp_line
			(start -0.2794 0.9906)
			(end 0.2794 0.9906)
			(stroke
				(width 0.1)
				(type default)
			)
			(layer "F.Fab")
		)
		(fp_line
			(start 0.2794 -0.1016)
			(end -0.2794 -0.1016)
			(stroke
				(width 0.1)
				(type default)
			)
			(layer "F.Fab")
		)
		(fp_line
			(start 0.2794 0.9906)
			(end 0.2794 -0.1016)
			(stroke
				(width 0.1)
				(type default)
			)
			(layer "F.Fab")
		)
		(pad "1" smd rect
			(at 0 0)
			(size 0.508 0.508)
			(layers "F.Cu" "F.Mask" "F.Paste")
			(net "P3V3_STBY")
		)
		(pad "2" smd rect
			(at 0 0.889)
			(size 0.508 0.508)
			(layers "F.Cu" "F.Mask" "F.Paste")
			(net "GPIOS7")
		)
		(zone
			(layer "F.Cu")
			(hatch none 0.5)
			(connect_pads
				(clearance 0)
			)
			(min_thickness 0.25)
			(keepout
				(tracks allowed)
				(vias not_allowed)
				(pads allowed)
				(copperpour not_allowed)
				(footprints allowed)
			)
			(placement
				(enabled no)
				(sheetname "")
			)
			(fill
				(thermal_gap 0.5)
				(thermal_bridge_width 0.5)
				(island_removal_mode 0)
			)
			(polygon
				(pts
					(xy 425.665646 -48.714152) (xy 426.173646 -48.714152) (xy 426.173646 -48.333152) (xy 425.665646 -48.333152)
				)
			)
		)
		(zone
			(layer "F.Cu")
			(hatch none 0.5)
			(connect_pads
				(clearance 0)
			)
			(min_thickness 0.25)
			(keepout
				(tracks not_allowed)
				(vias allowed)
				(pads allowed)
				(copperpour not_allowed)
				(footprints allowed)
			)
			(placement
				(enabled no)
				(sheetname "")
			)
			(fill
				(thermal_gap 0.5)
				(thermal_bridge_width 0.5)
				(island_removal_mode 0)
			)
			(polygon
				(pts
					(xy 425.665646 -48.333152) (xy 426.173646 -48.333152) (xy 426.173646 -48.714152) (xy 425.665646 -48.714152)
				)
			)
		)
	)
	(footprint ""
		(layer "F.Cu")
		(at 99.769168 -84.7598)
		(property "Reference" "C2D4"
			(at 0 0 0)
			(layer "F.SilkS")
			(hide yes)
			(effects
				(font
					(size 1.27 1.27)
				)
			)
		)
		(property "Value" ""
			(at 0 0 0)
			(layer "F.Fab")
			(effects
				(font
					(size 1.27 1.27)
				)
			)
		)
		(duplicate_pad_numbers_are_jumpers no)
		(fp_poly
			(pts
				(xy -0.4953 -0.2032) (xy 0.4953 -0.2032) (xy 0.4953 1.6002) (xy -0.4953 1.6002)
			)
			(stroke
				(width 0)
				(type default)
			)
			(fill no)
			(layer "F.CrtYd")
		)
		(fp_line
			(start -0.4953 -0.2032)
			(end 0.4953 -0.2032)
			(stroke
				(width 0.1)
				(type default)
			)
			(layer "F.Fab")
		)
		(fp_line
			(start -0.4953 1.6002)
			(end -0.4953 -0.2032)
			(stroke
				(width 0.1)
				(type default)
			)
			(layer "F.Fab")
		)
		(fp_line
			(start 0.4953 -0.2032)
			(end 0.4953 1.6002)
			(stroke
				(width 0.1)
				(type default)
			)
			(layer "F.Fab")
		)
		(fp_line
			(start 0.4953 1.6002)
			(end -0.4953 1.6002)
			(stroke
				(width 0.1)
				(type default)
			)
			(layer "F.Fab")
		)
		(pad "1" smd rect
			(at 0 0)
			(size 0.762 0.889)
			(layers "F.Cu" "F.Mask" "F.Paste")
			(net "PVDDQ_KLM")
		)
		(pad "2" smd rect
			(at 0 1.397)
			(size 0.762 0.889)
			(layers "F.Cu" "F.Mask" "F.Paste")
			(net "GND")
		)
		(zone
			(layer "F.Cu")
			(hatch none 0.5)
			(connect_pads
				(clearance 0)
			)
			(min_thickness 0.25)
			(keepout
				(tracks not_allowed)
				(vias allowed)
				(pads allowed)
				(copperpour not_allowed)
				(footprints allowed)
			)
			(placement
				(enabled no)
				(sheetname "")
			)
			(fill
				(thermal_gap 0.5)
				(thermal_bridge_width 0.5)
				(island_removal_mode 0)
			)
			(polygon
				(pts
					(xy 99.388168 -84.3153) (xy 100.150168 -84.3153) (xy 100.150168 -83.8073) (xy 99.388168 -83.8073)
				)
			)
		)
	)
	(footprint ""
		(layer "F.Cu")
		(at 387.96976 -139.5222)
		(property "Reference" "C7A42"
			(at 0 0 0)
			(layer "F.SilkS")
			(hide yes)
			(effects
				(font
					(size 1.27 1.27)
				)
			)
		)
		(property "Value" ""
			(at 0 0 0)
			(layer "F.Fab")
			(effects
				(font
					(size 1.27 1.27)
				)
			)
		)
		(duplicate_pad_numbers_are_jumpers no)
		(fp_rect
			(start 0.7239 1.9939)
			(end -0.7239 -0.2159)
			(stroke
				(width 0)
				(type default)
			)
			(fill no)
			(layer "F.CrtYd")
		)
		(fp_line
			(start -0.7239 -0.2159)
			(end -0.7239 1.9939)
			(stroke
				(width 0.1)
				(type default)
			)
			(layer "F.Fab")
		)
		(fp_line
			(start -0.7239 1.9939)
			(end 0.7239 1.9939)
			(stroke
				(width 0.1)
				(type default)
			)
			(layer "F.Fab")
		)
		(fp_line
			(start 0.7239 -0.2159)
			(end -0.7239 -0.2159)
			(stroke
				(width 0.1)
				(type default)
			)
			(layer "F.Fab")
		)
		(fp_line
			(start 0.7239 1.9939)
			(end 0.7239 -0.2159)
			(stroke
				(width 0.1)
				(type default)
			)
			(layer "F.Fab")
		)
		(pad "1" smd rect
			(at 0 0)
			(size 1.27 1.016)
			(layers "F.Cu" "F.Mask" "F.Paste")
			(net "P1V05_PCH_STBY")
		)
		(pad "2" smd rect
			(at 0 1.778)
			(size 1.27 1.016)
			(layers "F.Cu" "F.Mask" "F.Paste")
			(net "GND")
		)
		(zone
			(layer "F.Cu")
			(hatch none 0.5)
			(connect_pads
				(clearance 0)
			)
			(min_thickness 0.25)
			(keepout
				(tracks not_allowed)
				(vias allowed)
				(pads allowed)
				(copperpour not_allowed)
				(footprints allowed)
			)
			(placement
				(enabled no)
				(sheetname "")
			)
			(fill
				(thermal_gap 0.5)
				(thermal_bridge_width 0.5)
				(island_removal_mode 0)
			)
			(polygon
				(pts
					(xy 388.60476 -138.2522) (xy 388.60476 -139.0142) (xy 387.33476 -139.0142) (xy 387.33476 -138.2522)
				)
			)
		)
	)
	(footprint ""
		(layer "F.Cu")
		(at 386.45338 -140.14704 -90)
		(property "Reference" "C7B15"
			(at 0 0 270)
			(layer "F.SilkS")
			(hide yes)
			(effects
				(font
					(size 1.27 1.27)
				)
			)
		)
		(property "Value" ""
			(at 0 0 270)
			(layer "F.Fab")
			(effects
				(font
					(size 1.27 1.27)
				)
			)
		)
		(duplicate_pad_numbers_are_jumpers no)
		(fp_rect
			(start -0.4953 1.6002)
			(end 0.4953 -0.2032)
			(stroke
				(width 0)
				(type default)
			)
			(fill no)
			(layer "F.CrtYd")
		)
		(fp_line
			(start -0.4953 1.6002)
			(end -0.4953 -0.2032)
			(stroke
				(width 0.1)
				(type default)
			)
			(layer "F.Fab")
		)
		(fp_line
			(start 0.4953 1.6002)
			(end -0.4953 1.6002)
			(stroke
				(width 0.1)
				(type default)
			)
			(layer "F.Fab")
		)
		(fp_line
			(start -0.4953 -0.2032)
			(end 0.4953 -0.2032)
			(stroke
				(width 0.1)
				(type default)
			)
			(layer "F.Fab")
		)
		(fp_line
			(start 0.4953 -0.2032)
			(end 0.4953 1.6002)
			(stroke
				(width 0.1)
				(type default)
			)
			(layer "F.Fab")
		)
		(pad "1" smd rect
			(at 0 0 270)
			(size 0.762 0.889)
			(layers "F.Cu" "F.Mask" "F.Paste")
			(net "P1V05_PCH_STBY")
		)
		(pad "2" smd rect
			(at 0 1.397 270)
			(size 0.762 0.889)
			(layers "F.Cu" "F.Mask" "F.Paste")
			(net "GND")
		)
		(zone
			(layer "F.Cu")
			(hatch none 0.5)
			(connect_pads
				(clearance 0)
			)
			(min_thickness 0.25)
			(keepout
				(tracks not_allowed)
				(vias allowed)
				(pads allowed)
				(copperpour not_allowed)
				(footprints allowed)
			)
			(placement
				(enabled no)
				(sheetname "")
			)
			(fill
				(thermal_gap 0.5)
				(thermal_bridge_width 0.5)
				(island_removal_mode 0)
			)
			(polygon
				(pts
					(xy 385.50088 -140.52804) (xy 385.50088 -139.76604) (xy 386.00888 -139.76604) (xy 386.00888 -140.52804)
				)
			)
		)
	)
	(footprint ""
		(layer "F.Cu")
		(at 167.294052 -73.056242 180)
		(property "Reference" "R4D41"
			(at 0 0 180)
			(layer "F.SilkS")
			(hide yes)
			(effects
				(font
					(size 1.27 1.27)
				)
			)
		)
		(property "Value" ""
			(at 0 0 180)
			(layer "F.Fab")
			(effects
				(font
					(size 1.27 1.27)
				)
			)
		)
		(duplicate_pad_numbers_are_jumpers no)
		(fp_poly
			(pts
				(xy -0.2794 -0.1016) (xy 0.2794 -0.1016) (xy 0.2794 0.9906) (xy -0.2794 0.9906)
			)
			(stroke
				(width 0)
				(type default)
			)
			(fill no)
			(layer "F.CrtYd")
		)
		(fp_line
			(start 0.2794 0.9906)
			(end 0.2794 -0.1016)
			(stroke
				(width 0.1)
				(type default)
			)
			(layer "F.Fab")
		)
		(fp_line
			(start 0.2794 -0.1016)
			(end -0.2794 -0.1016)
			(stroke
				(width 0.1)
				(type default)
			)
			(layer "F.Fab")
		)
		(fp_line
			(start -0.2794 0.9906)
			(end 0.2794 0.9906)
			(stroke
				(width 0.1)
				(type default)
			)
			(layer "F.Fab")
		)
		(fp_line
			(start -0.2794 -0.1016)
			(end -0.2794 0.9906)
			(stroke
				(width 0.1)
				(type default)
			)
			(layer "F.Fab")
		)
		(pad "1" smd rect
			(at 0 0 180)
			(size 0.508 0.508)
			(layers "F.Cu" "F.Mask" "F.Paste")
			(net "P3V3_DB1200")
		)
		(pad "2" smd rect
			(at 0 0.889 180)
			(size 0.508 0.508)
			(layers "F.Cu" "F.Mask" "F.Paste")
			(net "FM_HBW_BYPASS_LOWBW_N")
		)
		(zone
			(layer "F.Cu")
			(hatch none 0.5)
			(connect_pads
				(clearance 0)
			)
			(min_thickness 0.25)
			(keepout
				(tracks not_allowed)
				(vias allowed)
				(pads allowed)
				(copperpour not_allowed)
				(footprints allowed)
			)
			(placement
				(enabled no)
				(sheetname "")
			)
			(fill
				(thermal_gap 0.5)
				(thermal_bridge_width 0.5)
				(island_removal_mode 0)
			)
			(polygon
				(pts
					(xy 167.548052 -73.691242) (xy 167.040052 -73.691242) (xy 167.040052 -73.310242) (xy 167.548052 -73.310242)
				)
			)
		)
		(zone
			(layer "F.Cu")
			(hatch none 0.5)
			(connect_pads
				(clearance 0)
			)
			(min_thickness 0.25)
			(keepout
				(tracks allowed)
				(vias not_allowed)
				(pads allowed)
				(copperpour not_allowed)
				(footprints allowed)
			)
			(placement
				(enabled no)
				(sheetname "")
			)
			(fill
				(thermal_gap 0.5)
				(thermal_bridge_width 0.5)
				(island_removal_mode 0)
			)
			(polygon
				(pts
					(xy 167.548052 -73.310242) (xy 167.040052 -73.310242) (xy 167.040052 -73.691242) (xy 167.548052 -73.691242)
				)
			)
		)
	)
	(footprint ""
		(layer "F.Cu")
		(at 437.769 -13.843)
		(property "Reference" "R1U58"
			(at 0 0 0)
			(layer "F.SilkS")
			(hide yes)
			(effects
				(font
					(size 1.27 1.27)
				)
			)
		)
		(property "Value" ""
			(at 0 0 0)
			(layer "F.Fab")
			(effects
				(font
					(size 1.27 1.27)
				)
			)
		)
		(duplicate_pad_numbers_are_jumpers no)
		(fp_poly
			(pts
				(xy -0.2794 -0.1016) (xy 0.2794 -0.1016) (xy 0.2794 0.9906) (xy -0.2794 0.9906)
			)
			(stroke
				(width 0)
				(type default)
			)
			(fill no)
			(layer "F.CrtYd")
		)
		(fp_line
			(start -0.2794 -0.1016)
			(end -0.2794 0.9906)
			(stroke
				(width 0.1)
				(type default)
			)
			(layer "F.Fab")
		)
		(fp_line
			(start -0.2794 0.9906)
			(end 0.2794 0.9906)
			(stroke
				(width 0.1)
				(type default)
			)
			(layer "F.Fab")
		)
		(fp_line
			(start 0.2794 -0.1016)
			(end -0.2794 -0.1016)
			(stroke
				(width 0.1)
				(type default)
			)
			(layer "F.Fab")
		)
		(fp_line
			(start 0.2794 0.9906)
			(end 0.2794 -0.1016)
			(stroke
				(width 0.1)
				(type default)
			)
			(layer "F.Fab")
		)
		(pad "1" smd rect
			(at 0 0)
			(size 0.508 0.508)
			(layers "F.Cu" "F.Mask" "F.Paste")
			(net "H_CPU0_MEMDEF_MEMHOT_G_N")
		)
		(pad "2" smd rect
			(at 0 0.889)
			(size 0.508 0.508)
			(layers "F.Cu" "F.Mask" "F.Paste")
			(net "H_CPU0_MEMDEF_MEMHOT_G_R_N")
		)
		(zone
			(layer "F.Cu")
			(hatch none 0.5)
			(connect_pads
				(clearance 0)
			)
			(min_thickness 0.25)
			(keepout
				(tracks allowed)
				(vias not_allowed)
				(pads allowed)
				(copperpour not_allowed)
				(footprints allowed)
			)
			(placement
				(enabled no)
				(sheetname "")
			)
			(fill
				(thermal_gap 0.5)
				(thermal_bridge_width 0.5)
				(island_removal_mode 0)
			)
			(polygon
				(pts
					(xy 437.515 -13.589) (xy 438.023 -13.589) (xy 438.023 -13.208) (xy 437.515 -13.208)
				)
			)
		)
		(zone
			(layer "F.Cu")
			(hatch none 0.5)
			(connect_pads
				(clearance 0)
			)
			(min_thickness 0.25)
			(keepout
				(tracks not_allowed)
				(vias allowed)
				(pads allowed)
				(copperpour not_allowed)
				(footprints allowed)
			)
			(placement
				(enabled no)
				(sheetname "")
			)
			(fill
				(thermal_gap 0.5)
				(thermal_bridge_width 0.5)
				(island_removal_mode 0)
			)
			(polygon
				(pts
					(xy 437.515 -13.208) (xy 438.023 -13.208) (xy 438.023 -13.589) (xy 437.515 -13.589)
				)
			)
		)
	)
	(footprint ""
		(layer "F.Cu")
		(at 183.007 -61.976 180)
		(property "Reference" "R4E9"
			(at 0 0 180)
			(layer "F.SilkS")
			(hide yes)
			(effects
				(font
					(size 1.27 1.27)
				)
			)
		)
		(property "Value" ""
			(at 0 0 180)
			(layer "F.Fab")
			(effects
				(font
					(size 1.27 1.27)
				)
			)
		)
		(duplicate_pad_numbers_are_jumpers no)
		(fp_rect
			(start 0.2794 -0.1016)
			(end -0.2794 0.9906)
			(stroke
				(width 0)
				(type default)
			)
			(fill no)
			(layer "F.CrtYd")
		)
		(fp_line
			(start 0.2794 0.9906)
			(end 0.2794 -0.1016)
			(stroke
				(width 0.1)
				(type default)
			)
			(layer "F.Fab")
		)
		(fp_line
			(start 0.2794 -0.1016)
			(end -0.2794 -0.1016)
			(stroke
				(width 0.1)
				(type default)
			)
			(layer "F.Fab")
		)
		(fp_line
			(start -0.2794 0.9906)
			(end 0.2794 0.9906)
			(stroke
				(width 0.1)
				(type default)
			)
			(layer "F.Fab")
		)
		(fp_line
			(start -0.2794 -0.1016)
			(end -0.2794 0.9906)
			(stroke
				(width 0.1)
				(type default)
			)
			(layer "F.Fab")
		)
		(pad "1" smd rect
			(at 0 0 180)
			(size 0.508 0.508)
			(layers "F.Cu" "F.Mask" "F.Paste")
			(net "PVCCIO_CPU0")
		)
		(pad "2" smd rect
			(at 0 0.889 180)
			(size 0.508 0.508)
			(layers "F.Cu" "F.Mask" "F.Paste")
			(net "SVID_CLK0_CPU0_R")
		)
		(zone
			(layer "F.Cu")
			(hatch none 0.5)
			(connect_pads
				(clearance 0)
			)
			(min_thickness 0.25)
			(keepout
				(tracks not_allowed)
				(vias allowed)
				(pads allowed)
				(copperpour not_allowed)
				(footprints allowed)
			)
			(placement
				(enabled no)
				(sheetname "")
			)
			(fill
				(thermal_gap 0.5)
				(thermal_bridge_width 0.5)
				(island_removal_mode 0)
			)
			(polygon
				(pts
					(xy 182.753 -62.23) (xy 183.261 -62.23) (xy 183.261 -62.611) (xy 182.753 -62.611)
				)
			)
		)
		(zone
			(layer "F.Cu")
			(hatch none 0.5)
			(connect_pads
				(clearance 0)
			)
			(min_thickness 0.25)
			(keepout
				(tracks allowed)
				(vias not_allowed)
				(pads allowed)
				(copperpour not_allowed)
				(footprints allowed)
			)
			(placement
				(enabled no)
				(sheetname "")
			)
			(fill
				(thermal_gap 0.5)
				(thermal_bridge_width 0.5)
				(island_removal_mode 0)
			)
			(polygon
				(pts
					(xy 182.753 -62.23) (xy 183.261 -62.23) (xy 183.261 -62.611) (xy 182.753 -62.611)
				)
			)
		)
	)
	(footprint ""
		(layer "F.Cu")
		(at 102.145592 -68.412614 180)
		(property "Reference" "C2D44"
			(at 0 0 180)
			(layer "F.SilkS")
			(hide yes)
			(effects
				(font
					(size 1.27 1.27)
				)
			)
		)
		(property "Value" ""
			(at 0 0 180)
			(layer "F.Fab")
			(effects
				(font
					(size 1.27 1.27)
				)
			)
		)
		(duplicate_pad_numbers_are_jumpers no)
		(fp_poly
			(pts
				(xy -0.4953 -0.2032) (xy 0.4953 -0.2032) (xy 0.4953 1.6002) (xy -0.4953 1.6002)
			)
			(stroke
				(width 0)
				(type default)
			)
			(fill no)
			(layer "F.CrtYd")
		)
		(fp_line
			(start 0.4953 1.6002)
			(end -0.4953 1.6002)
			(stroke
				(width 0.1)
				(type default)
			)
			(layer "F.Fab")
		)
		(fp_line
			(start 0.4953 -0.2032)
			(end 0.4953 1.6002)
			(stroke
				(width 0.1)
				(type default)
			)
			(layer "F.Fab")
		)
		(fp_line
			(start -0.4953 1.6002)
			(end -0.4953 -0.2032)
			(stroke
				(width 0.1)
				(type default)
			)
			(layer "F.Fab")
		)
		(fp_line
			(start -0.4953 -0.2032)
			(end 0.4953 -0.2032)
			(stroke
				(width 0.1)
				(type default)
			)
			(layer "F.Fab")
		)
		(pad "1" smd rect
			(at 0 0 180)
			(size 0.762 0.889)
			(layers "F.Cu" "F.Mask" "F.Paste")
			(net "PVDDQ_GHJ")
		)
		(pad "2" smd rect
			(at 0 1.397 180)
			(size 0.762 0.889)
			(layers "F.Cu" "F.Mask" "F.Paste")
			(net "GND")
		)
		(zone
			(layer "F.Cu")
			(hatch none 0.5)
			(connect_pads
				(clearance 0)
			)
			(min_thickness 0.25)
			(keepout
				(tracks not_allowed)
				(vias allowed)
				(pads allowed)
				(copperpour not_allowed)
				(footprints allowed)
			)
			(placement
				(enabled no)
				(sheetname "")
			)
			(fill
				(thermal_gap 0.5)
				(thermal_bridge_width 0.5)
				(island_removal_mode 0)
			)
			(polygon
				(pts
					(xy 102.526592 -68.857114) (xy 101.764592 -68.857114) (xy 101.764592 -69.365114) (xy 102.526592 -69.365114)
				)
			)
		)
	)
)
